(kicad_pcb
	(version 20260206)
	(generator "pcbnew")
	(generator_version "10.0")
	(general
		(thickness 1.6)
		(legacy_teardrops no)
	)
	(paper "A4")
	(title_block
		(title "timecard-production-celestica-r4006 — R4006-B0001-02_R01.brd")
		(comment 1 "Time Appliance Project (Time Card) / footprints 1018-1023 of 1113")
	)
	(layers
		(0 "F.Cu" signal "TOP")
		(4 "In1.Cu" signal "L02_GND1")
		(6 "In2.Cu" signal "L03_SIG1")
		(8 "In3.Cu" signal "L04_GND2")
		(10 "In4.Cu" signal "L05_VCC1")
		(12 "In5.Cu" signal "L06_VCC2")
		(14 "In6.Cu" signal "L07_GND3")
		(16 "In7.Cu" signal "L08_SIG2")
		(18 "In8.Cu" signal "L09_GND4")
		(2 "B.Cu" signal "BOTTOM")
		(9 "F.Adhes" user "F.Adhesive")
		(11 "B.Adhes" user "B.Adhesive")
		(13 "F.Paste" user "Package Geometry/Pastemask Top")
		(15 "B.Paste" user "Package Geometry/Pastemask Bottom")
		(5 "F.SilkS" user "Ref Des/Silkscreen Top")
		(7 "B.SilkS" user "Ref Des/Silkscreen Bottom")
		(1 "F.Mask" user "Board Geometry/Soldermask Top")
		(3 "B.Mask" user "Board Geometry/Soldermask Bottom")
		(17 "Dwgs.User" user "User.Drawings")
		(19 "Cmts.User" user "User.Comments")
		(21 "Eco1.User" user "User.Eco1")
		(23 "Eco2.User" user "User.Eco2")
		(25 "Edge.Cuts" user "Board Geometry/Outline")
		(27 "Margin" user)
		(31 "F.CrtYd" user "Package Geometry/Place Bound Top")
		(29 "B.CrtYd" user "Package Geometry/Place Bound Bottom")
		(35 "F.Fab" user "Ref Des/Assembly Top")
		(33 "B.Fab" user "Ref Des/Assembly Bottom")
	)
	(footprint ""
		(layer "B.Cu")
		(at 68.784978 -15.367 -90)
		(property "Reference" "C27"
			(at 3.048 -0.144272 270)
			(unlocked yes)
			(layer "B.SilkS")
			(effects
				(font
					(size 0.635 0.4064)
					(thickness 0.1524)
				)
				(justify mirror)
			)
		)
		(property "Value" "VAL*"
			(at -0.0762 2.067306 270)
			(unlocked yes)
			(layer "B.Fab")
			(hide yes)
			(effects
				(font
					(size 0.7874 0.5842)
					(thickness 0.1524)
				)
				(justify mirror)
			)
		)
		(property "Tolerance" "TOL*"
			(at -0.0762 3.032506 270)
			(unlocked yes)
			(layer "Cmts.User")
			(hide yes)
			(effects
				(font
					(size 0.7874 0.5842)
					(thickness 0.1524)
				)
				(justify mirror)
			)
		)
		(property "User Part Number" "PARTNUM*"
			(at -0.1016 4.023106 270)
			(unlocked yes)
			(layer "Cmts.User")
			(hide yes)
			(effects
				(font
					(size 0.7874 0.5842)
					(thickness 0.1524)
				)
				(justify mirror)
			)
		)
		(property "Device Type" "CAPACITOR-G105-0B104-CK,0.1UF,A"
			(at -0.0508 1.127506 270)
			(unlocked yes)
			(layer "B.Fab")
			(hide yes)
			(effects
				(font
					(size 0.7874 0.5842)
					(thickness 0.1524)
				)
				(justify mirror)
			)
		)
		(duplicate_pad_numbers_are_jumpers no)
		(fp_line
			(start -1.143 0.5588)
			(end -1.143 -0.5588)
			(stroke
				(width 0.1)
				(type default)
			)
			(layer "B.SilkS")
		)
		(fp_line
			(start 1.143 0.5588)
			(end -1.143 0.5588)
			(stroke
				(width 0.1)
				(type default)
			)
			(layer "B.SilkS")
		)
		(fp_line
			(start -1.143 -0.5588)
			(end 1.143 -0.5588)
			(stroke
				(width 0.1)
				(type default)
			)
			(layer "B.SilkS")
		)
		(fp_line
			(start 1.143 -0.5588)
			(end 1.143 0.5588)
			(stroke
				(width 0.1)
				(type default)
			)
			(layer "B.SilkS")
		)
		(fp_rect
			(start 1.143 0.5588)
			(end -1.143 -0.5588)
			(stroke
				(width 0)
				(type default)
			)
			(fill no)
			(layer "B.CrtYd")
		)
		(fp_line
			(start -0.508 0.3048)
			(end -0.508 -0.3048)
			(stroke
				(width 0.1)
				(type default)
			)
			(layer "B.Fab")
		)
		(fp_line
			(start 0.508 0.3048)
			(end -0.508 0.3048)
			(stroke
				(width 0.1)
				(type default)
			)
			(layer "B.Fab")
		)
		(fp_line
			(start -0.508 -0.3048)
			(end 0.508 -0.3048)
			(stroke
				(width 0.1)
				(type default)
			)
			(layer "B.Fab")
		)
		(fp_line
			(start 0.508 -0.3048)
			(end 0.508 0.3048)
			(stroke
				(width 0.1)
				(type default)
			)
			(layer "B.Fab")
		)
		(pad "1" smd rect
			(at 0.5334 0 90)
			(size 0.7112 0.6096)
			(layers "B.Cu" "B.Mask" "B.Paste")
			(net "C_CPU_RX_PCIE_MGT1_TXN")
		)
		(pad "2" smd rect
			(at -0.5334 0 90)
			(size 0.7112 0.6096)
			(layers "B.Cu" "B.Mask" "B.Paste")
			(net "CPU_RX_PCIE_MGT1_TXN")
		)
		(zone
			(layer "B.Cu")
			(hatch none 0.5)
			(connect_pads
				(clearance 0)
			)
			(min_thickness 0.25)
			(keepout
				(tracks allowed)
				(vias not_allowed)
				(pads allowed)
				(copperpour not_allowed)
				(footprints allowed)
			)
			(placement
				(enabled no)
				(sheetname "")
			)
			(fill
				(thermal_gap 0.5)
				(thermal_bridge_width 0.5)
				(island_removal_mode 0)
			)
			(polygon
				(pts
					(xy 68.480178 -15.2908) (xy 69.089778 -15.2908) (xy 69.089778 -15.4432) (xy 68.480178 -15.4432)
				)
			)
		)
	)
	(footprint ""
		(layer "B.Cu")
		(at 109.4486 -37.211 -90)
		(property "Reference" "C142"
			(at 1.27 41.76395 270)
			(unlocked yes)
			(layer "B.SilkS")
			(effects
				(font
					(size 0.635 0.4064)
					(thickness 0.1524)
				)
				(justify mirror)
			)
		)
		(property "Value" "VAL*"
			(at 0 3.718306 270)
			(unlocked yes)
			(layer "B.Fab")
			(hide yes)
			(effects
				(font
					(size 0.7874 0.5842)
					(thickness 0.127)
				)
				(justify mirror)
			)
		)
		(property "Device Type" "CAPACITOR-G105-0B104-CK,0.1UF,A"
			(at 0 1.432306 270)
			(unlocked yes)
			(layer "B.Fab")
			(hide yes)
			(effects
				(font
					(size 0.7874 0.5842)
					(thickness 0.127)
				)
				(justify mirror)
			)
		)
		(property "User Part Number" "PARTNUM*"
			(at 0 2.575306 270)
			(unlocked yes)
			(layer "Cmts.User")
			(hide yes)
			(effects
				(font
					(size 0.7874 0.5842)
					(thickness 0.127)
				)
				(justify mirror)
			)
		)
		(property "Tolerance" "TOL*"
			(at 0 4.861306 270)
			(unlocked yes)
			(layer "Cmts.User")
			(hide yes)
			(effects
				(font
					(size 0.7874 0.5842)
					(thickness 0.127)
				)
				(justify mirror)
			)
		)
		(duplicate_pad_numbers_are_jumpers no)
		(fp_line
			(start -0.970026 0.4699)
			(end 0.970026 0.4699)
			(stroke
				(width 0.1)
				(type default)
			)
			(layer "B.SilkS")
		)
		(fp_line
			(start 0.970026 0.4699)
			(end 0.970026 -0.4699)
			(stroke
				(width 0.1)
				(type default)
			)
			(layer "B.SilkS")
		)
		(fp_line
			(start -0.970026 -0.4699)
			(end -0.970026 0.4699)
			(stroke
				(width 0.1)
				(type default)
			)
			(layer "B.SilkS")
		)
		(fp_line
			(start 0.970026 -0.4699)
			(end -0.970026 -0.4699)
			(stroke
				(width 0.1)
				(type default)
			)
			(layer "B.SilkS")
		)
		(fp_poly
			(pts
				(xy 0.970026 0.4699) (xy -0.970026 0.4699) (xy -0.970026 -0.4699) (xy 0.970026 -0.4699)
			)
			(stroke
				(width 0)
				(type default)
			)
			(fill no)
			(layer "B.CrtYd")
		)
		(fp_line
			(start -0.508 0.3048)
			(end 0.508 0.3048)
			(stroke
				(width 0.1)
				(type default)
			)
			(layer "B.Fab")
		)
		(fp_line
			(start 0.508 0.3048)
			(end 0.508 -0.3048)
			(stroke
				(width 0.1)
				(type default)
			)
			(layer "B.Fab")
		)
		(fp_line
			(start -0.508 -0.3048)
			(end -0.508 0.3048)
			(stroke
				(width 0.1)
				(type default)
			)
			(layer "B.Fab")
		)
		(fp_line
			(start 0.508 -0.3048)
			(end -0.508 -0.3048)
			(stroke
				(width 0.1)
				(type default)
			)
			(layer "B.Fab")
		)
		(pad "1" smd circle
			(at 0.500126 0 90)
			(size 0.635 0.635)
			(layers "B.Cu" "B.Mask" "B.Paste")
			(net "XP2R5V_FPGA")
		)
		(pad "2" smd circle
			(at -0.500126 0 90)
			(size 0.635 0.635)
			(layers "B.Cu" "B.Mask" "B.Paste")
			(net "SG")
		)
	)
	(footprint ""
		(layer "B.Cu")
		(at 36.9824 -101.3714)
		(property "Reference" "R30"
			(at -4.0386 0.64897 0)
			(unlocked yes)
			(layer "B.SilkS")
			(effects
				(font
					(size 0.7874 0.5842)
					(thickness 0.1524)
				)
				(justify mirror)
			)
		)
		(property "Value" "VAL*"
			(at -0.02032 2.13233 0)
			(unlocked yes)
			(layer "B.Fab")
			(hide yes)
			(effects
				(font
					(size 0.7874 0.5842)
					(thickness 0.1524)
				)
				(justify mirror)
			)
		)
		(property "Device Type" "RESISTOR-G155-12201-01,2.2KOHMA"
			(at -0.008382 1.210564 0)
			(unlocked yes)
			(layer "B.Fab")
			(hide yes)
			(effects
				(font
					(size 0.7874 0.5842)
					(thickness 0.1524)
				)
				(justify mirror)
			)
		)
		(property "User Part Number" "PARTNUM*"
			(at -0.02032 4.024884 0)
			(unlocked yes)
			(layer "Cmts.User")
			(hide yes)
			(effects
				(font
					(size 0.7874 0.5842)
					(thickness 0.1524)
				)
				(justify mirror)
			)
		)
		(property "Tolerance" "TOL*"
			(at -0.044704 3.05435 0)
			(unlocked yes)
			(layer "Cmts.User")
			(hide yes)
			(effects
				(font
					(size 0.7874 0.5842)
					(thickness 0.1524)
				)
				(justify mirror)
			)
		)
		(duplicate_pad_numbers_are_jumpers no)
		(fp_line
			(start -1.143 -0.5588)
			(end 1.143 -0.5588)
			(stroke
				(width 0.1)
				(type default)
			)
			(layer "B.SilkS")
		)
		(fp_line
			(start -1.143 0.5588)
			(end -1.143 -0.5588)
			(stroke
				(width 0.1)
				(type default)
			)
			(layer "B.SilkS")
		)
		(fp_line
			(start 1.143 -0.5588)
			(end 1.143 0.5588)
			(stroke
				(width 0.1)
				(type default)
			)
			(layer "B.SilkS")
		)
		(fp_line
			(start 1.143 0.5588)
			(end -1.143 0.5588)
			(stroke
				(width 0.1)
				(type default)
			)
			(layer "B.SilkS")
		)
		(fp_rect
			(start 1.143 -0.5588)
			(end -1.143 0.5588)
			(stroke
				(width 0)
				(type default)
			)
			(fill no)
			(layer "B.CrtYd")
		)
		(fp_line
			(start -0.508 -0.3048)
			(end 0.508 -0.3048)
			(stroke
				(width 0.1)
				(type default)
			)
			(layer "B.Fab")
		)
		(fp_line
			(start -0.508 0.3048)
			(end -0.508 -0.3048)
			(stroke
				(width 0.1)
				(type default)
			)
			(layer "B.Fab")
		)
		(fp_line
			(start 0.508 -0.3048)
			(end 0.508 0.3048)
			(stroke
				(width 0.1)
				(type default)
			)
			(layer "B.Fab")
		)
		(fp_line
			(start 0.508 0.3048)
			(end -0.508 0.3048)
			(stroke
				(width 0.1)
				(type default)
			)
			(layer "B.Fab")
		)
		(pad "1" smd rect
			(at 0.5334 0 180)
			(size 0.7112 0.6096)
			(layers "B.Cu" "B.Mask" "B.Paste")
			(net "XP5R0V_COMP")
		)
		(pad "2" smd rect
			(at -0.5334 0 180)
			(size 0.7112 0.6096)
			(layers "B.Cu" "B.Mask" "B.Paste")
			(net "UNNAMED_516_CAPACITOR_I13_1")
		)
		(zone
			(layer "B.Cu")
			(hatch none 0.5)
			(connect_pads
				(clearance 0)
			)
			(min_thickness 0.25)
			(keepout
				(tracks allowed)
				(vias not_allowed)
				(pads allowed)
				(copperpour not_allowed)
				(footprints allowed)
			)
			(placement
				(enabled no)
				(sheetname "")
			)
			(fill
				(thermal_gap 0.5)
				(thermal_bridge_width 0.5)
				(island_removal_mode 0)
			)
			(polygon
				(pts
					(xy 37.0586 -101.6762) (xy 36.9062 -101.6762) (xy 36.9062 -101.0666) (xy 37.0586 -101.0666)
				)
			)
		)
	)
	(footprint ""
		(layer "B.Cu")
		(at 110.847124 -41.32326 -90)
		(property "Reference" "C129"
			(at 0.81026 42.044874 270)
			(unlocked yes)
			(layer "B.SilkS")
			(effects
				(font
					(size 0.635 0.4064)
					(thickness 0.1524)
				)
				(justify mirror)
			)
		)
		(property "Value" "VAL*"
			(at 0 3.718306 270)
			(unlocked yes)
			(layer "B.Fab")
			(hide yes)
			(effects
				(font
					(size 0.7874 0.5842)
					(thickness 0.127)
				)
				(justify mirror)
			)
		)
		(property "Tolerance" "TOL*"
			(at 0 4.861306 270)
			(unlocked yes)
			(layer "Cmts.User")
			(hide yes)
			(effects
				(font
					(size 0.7874 0.5842)
					(thickness 0.127)
				)
				(justify mirror)
			)
		)
		(property "User Part Number" "PARTNUM*"
			(at 0 2.575306 270)
			(unlocked yes)
			(layer "Cmts.User")
			(hide yes)
			(effects
				(font
					(size 0.7874 0.5842)
					(thickness 0.127)
				)
				(justify mirror)
			)
		)
		(property "Device Type" "CAPACITOR-G105-0B104-CK,0.1UF,A"
			(at 0 1.432306 270)
			(unlocked yes)
			(layer "B.Fab")
			(hide yes)
			(effects
				(font
					(size 0.7874 0.5842)
					(thickness 0.127)
				)
				(justify mirror)
			)
		)
		(duplicate_pad_numbers_are_jumpers no)
		(fp_line
			(start -0.970026 0.4699)
			(end 0.970026 0.4699)
			(stroke
				(width 0.1)
				(type default)
			)
			(layer "B.SilkS")
		)
		(fp_line
			(start 0.970026 0.4699)
			(end 0.970026 -0.4699)
			(stroke
				(width 0.1)
				(type default)
			)
			(layer "B.SilkS")
		)
		(fp_line
			(start -0.970026 -0.4699)
			(end -0.970026 0.4699)
			(stroke
				(width 0.1)
				(type default)
			)
			(layer "B.SilkS")
		)
		(fp_line
			(start 0.970026 -0.4699)
			(end -0.970026 -0.4699)
			(stroke
				(width 0.1)
				(type default)
			)
			(layer "B.SilkS")
		)
		(fp_poly
			(pts
				(xy 0.970026 0.4699) (xy -0.970026 0.4699) (xy -0.970026 -0.4699) (xy 0.970026 -0.4699)
			)
			(stroke
				(width 0)
				(type default)
			)
			(fill no)
			(layer "B.CrtYd")
		)
		(fp_line
			(start -0.508 0.3048)
			(end 0.508 0.3048)
			(stroke
				(width 0.1)
				(type default)
			)
			(layer "B.Fab")
		)
		(fp_line
			(start 0.508 0.3048)
			(end 0.508 -0.3048)
			(stroke
				(width 0.1)
				(type default)
			)
			(layer "B.Fab")
		)
		(fp_line
			(start -0.508 -0.3048)
			(end -0.508 0.3048)
			(stroke
				(width 0.1)
				(type default)
			)
			(layer "B.Fab")
		)
		(fp_line
			(start 0.508 -0.3048)
			(end -0.508 -0.3048)
			(stroke
				(width 0.1)
				(type default)
			)
			(layer "B.Fab")
		)
		(pad "1" smd circle
			(at 0.500126 0 90)
			(size 0.635 0.635)
			(layers "B.Cu" "B.Mask" "B.Paste")
			(net "XP1R0V_FPGA_VCCINT")
		)
		(pad "2" smd circle
			(at -0.500126 0 90)
			(size 0.635 0.635)
			(layers "B.Cu" "B.Mask" "B.Paste")
			(net "SG")
		)
	)
	(footprint ""
		(layer "B.Cu")
		(at 76.784962 -15.367 -90)
		(property "Reference" "C36"
			(at -1.778 -2.169668 270)
			(unlocked yes)
			(layer "B.SilkS")
			(effects
				(font
					(size 0.7874 0.5842)
					(thickness 0.1524)
				)
				(justify mirror)
			)
		)
		(property "Value" "VAL*"
			(at -0.0762 2.067306 270)
			(unlocked yes)
			(layer "B.Fab")
			(hide yes)
			(effects
				(font
					(size 0.7874 0.5842)
					(thickness 0.1524)
				)
				(justify mirror)
			)
		)
		(property "Tolerance" "TOL*"
			(at -0.0762 3.032506 270)
			(unlocked yes)
			(layer "Cmts.User")
			(hide yes)
			(effects
				(font
					(size 0.7874 0.5842)
					(thickness 0.1524)
				)
				(justify mirror)
			)
		)
		(property "User Part Number" "PARTNUM*"
			(at -0.1016 4.023106 270)
			(unlocked yes)
			(layer "Cmts.User")
			(hide yes)
			(effects
				(font
					(size 0.7874 0.5842)
					(thickness 0.1524)
				)
				(justify mirror)
			)
		)
		(property "Device Type" "CAPACITOR-G105-0B104-CK,0.1UF,A"
			(at -0.0508 1.127506 270)
			(unlocked yes)
			(layer "B.Fab")
			(hide yes)
			(effects
				(font
					(size 0.7874 0.5842)
					(thickness 0.1524)
				)
				(justify mirror)
			)
		)
		(duplicate_pad_numbers_are_jumpers no)
		(fp_line
			(start -1.143 0.5588)
			(end -1.143 -0.5588)
			(stroke
				(width 0.1)
				(type default)
			)
			(layer "B.SilkS")
		)
		(fp_line
			(start 1.143 0.5588)
			(end -1.143 0.5588)
			(stroke
				(width 0.1)
				(type default)
			)
			(layer "B.SilkS")
		)
		(fp_line
			(start -1.143 -0.5588)
			(end 1.143 -0.5588)
			(stroke
				(width 0.1)
				(type default)
			)
			(layer "B.SilkS")
		)
		(fp_line
			(start 1.143 -0.5588)
			(end 1.143 0.5588)
			(stroke
				(width 0.1)
				(type default)
			)
			(layer "B.SilkS")
		)
		(fp_rect
			(start 1.143 0.5588)
			(end -1.143 -0.5588)
			(stroke
				(width 0)
				(type default)
			)
			(fill no)
			(layer "B.CrtYd")
		)
		(fp_line
			(start -0.508 0.3048)
			(end -0.508 -0.3048)
			(stroke
				(width 0.1)
				(type default)
			)
			(layer "B.Fab")
		)
		(fp_line
			(start 0.508 0.3048)
			(end -0.508 0.3048)
			(stroke
				(width 0.1)
				(type default)
			)
			(layer "B.Fab")
		)
		(fp_line
			(start -0.508 -0.3048)
			(end 0.508 -0.3048)
			(stroke
				(width 0.1)
				(type default)
			)
			(layer "B.Fab")
		)
		(fp_line
			(start 0.508 -0.3048)
			(end 0.508 0.3048)
			(stroke
				(width 0.1)
				(type default)
			)
			(layer "B.Fab")
		)
		(pad "1" smd rect
			(at 0.5334 0 90)
			(size 0.7112 0.6096)
			(layers "B.Cu" "B.Mask" "B.Paste")
			(net "C_CPU_RX_PCIE_MGT3_TXN")
		)
		(pad "2" smd rect
			(at -0.5334 0 90)
			(size 0.7112 0.6096)
			(layers "B.Cu" "B.Mask" "B.Paste")
			(net "CPU_RX_PCIE_MGT3_TXN")
		)
		(zone
			(layer "B.Cu")
			(hatch none 0.5)
			(connect_pads
				(clearance 0)
			)
			(min_thickness 0.25)
			(keepout
				(tracks allowed)
				(vias not_allowed)
				(pads allowed)
				(copperpour not_allowed)
				(footprints allowed)
			)
			(placement
				(enabled no)
				(sheetname "")
			)
			(fill
				(thermal_gap 0.5)
				(thermal_bridge_width 0.5)
				(island_removal_mode 0)
			)
			(polygon
				(pts
					(xy 76.480162 -15.2908) (xy 77.089762 -15.2908) (xy 77.089762 -15.4432) (xy 76.480162 -15.4432)
				)
			)
		)
	)
	(footprint ""
		(layer "B.Cu")
		(at 76.708 -50.927 180)
		(property "Reference" "C65"
			(at -3.175 0.08763 0)
			(unlocked yes)
			(layer "B.SilkS")
			(effects
				(font
					(size 0.7874 0.5842)
					(thickness 0.1524)
				)
				(justify mirror)
			)
		)
		(property "Value" "VAL*"
			(at -0.0762 2.067306 180)
			(unlocked yes)
			(layer "B.Fab")
			(hide yes)
			(effects
				(font
					(size 0.7874 0.5842)
					(thickness 0.1524)
				)
				(justify mirror)
			)
		)
		(property "Tolerance" "TOL*"
			(at -0.0762 3.032506 180)
			(unlocked yes)
			(layer "Cmts.User")
			(hide yes)
			(effects
				(font
					(size 0.7874 0.5842)
					(thickness 0.1524)
				)
				(justify mirror)
			)
		)
		(property "User Part Number" "PARTNUM*"
			(at -0.1016 4.023106 180)
			(unlocked yes)
			(layer "Cmts.User")
			(hide yes)
			(effects
				(font
					(size 0.7874 0.5842)
					(thickness 0.1524)
				)
				(justify mirror)
			)
		)
		(property "Device Type" "CAPACITOR-G105-0B104-EK,0.1UF,A"
			(at -0.0508 1.127506 180)
			(unlocked yes)
			(layer "B.Fab")
			(hide yes)
			(effects
				(font
					(size 0.7874 0.5842)
					(thickness 0.1524)
				)
				(justify mirror)
			)
		)
		(duplicate_pad_numbers_are_jumpers no)
		(fp_line
			(start 1.143 0.5588)
			(end -1.143 0.5588)
			(stroke
				(width 0.1)
				(type default)
			)
			(layer "B.SilkS")
		)
		(fp_line
			(start 1.143 -0.5588)
			(end 1.143 0.5588)
			(stroke
				(width 0.1)
				(type default)
			)
			(layer "B.SilkS")
		)
		(fp_line
			(start -1.143 0.5588)
			(end -1.143 -0.5588)
			(stroke
				(width 0.1)
				(type default)
			)
			(layer "B.SilkS")
		)
		(fp_line
			(start -1.143 -0.5588)
			(end 1.143 -0.5588)
			(stroke
				(width 0.1)
				(type default)
			)
			(layer "B.SilkS")
		)
		(fp_rect
			(start 1.143 0.5588)
			(end -1.143 -0.5588)
			(stroke
				(width 0)
				(type default)
			)
			(fill no)
			(layer "B.CrtYd")
		)
		(fp_line
			(start 0.508 0.3048)
			(end -0.508 0.3048)
			(stroke
				(width 0.1)
				(type default)
			)
			(layer "B.Fab")
		)
		(fp_line
			(start 0.508 -0.3048)
			(end 0.508 0.3048)
			(stroke
				(width 0.1)
				(type default)
			)
			(layer "B.Fab")
		)
		(fp_line
			(start -0.508 0.3048)
			(end -0.508 -0.3048)
			(stroke
				(width 0.1)
				(type default)
			)
			(layer "B.Fab")
		)
		(fp_line
			(start -0.508 -0.3048)
			(end 0.508 -0.3048)
			(stroke
				(width 0.1)
				(type default)
			)
			(layer "B.Fab")
		)
		(pad "1" smd rect
			(at 0.5334 0)
			(size 0.7112 0.6096)
			(layers "B.Cu" "B.Mask" "B.Paste")
			(net "XP5R0V_MAC_USB")
		)
		(pad "2" smd rect
			(at -0.5334 0)
			(size 0.7112 0.6096)
			(layers "B.Cu" "B.Mask" "B.Paste")
			(net "SG")
		)
		(zone
			(layer "B.Cu")
			(hatch none 0.5)
			(connect_pads
				(clearance 0)
			)
			(min_thickness 0.25)
			(keepout
				(tracks allowed)
				(vias not_allowed)
				(pads allowed)
				(copperpour not_allowed)
				(footprints allowed)
			)
			(placement
				(enabled no)
				(sheetname "")
			)
			(fill
				(thermal_gap 0.5)
				(thermal_bridge_width 0.5)
				(island_removal_mode 0)
			)
			(polygon
				(pts
					(xy 76.6318 -51.2318) (xy 76.6318 -50.6222) (xy 76.7842 -50.6222) (xy 76.7842 -51.2318)
				)
			)
		)
	)
)
